(kicad_pcb
	(version 20260206)
	(generator "pcbnew")
	(generator_version "10.0")
	(general
		(thickness 1.6)
		(legacy_teardrops no)
	)
	(paper "A4")
	(title_block
		(title "01162023_DA0F0TEBIF0_F0T_Expander_BD_F_brd_V02_OCP.brd")
		(comment 1 "Grand Teton / footprints 4200-4207 of 9728")
	)
	(layers
		(0 "F.Cu" signal "TOP")
		(4 "In1.Cu" signal "GND")
		(6 "In2.Cu" signal "VCC")
		(8 "In3.Cu" signal "VCC1")
		(10 "In4.Cu" signal "GND1")
		(12 "In5.Cu" signal "IN1")
		(14 "In6.Cu" signal "GND2")
		(16 "In7.Cu" signal "IN2")
		(18 "In8.Cu" signal "GND3")
		(20 "In9.Cu" signal "IN3")
		(22 "In10.Cu" signal "GND4")
		(24 "In11.Cu" signal "IN4")
		(26 "In12.Cu" signal "GND5")
		(28 "In13.Cu" signal "IN5")
		(30 "In14.Cu" signal "GND6")
		(32 "In15.Cu" signal "IN6")
		(34 "In16.Cu" signal "GND7")
		(2 "B.Cu" signal "BOTTOM")
		(9 "F.Adhes" user "F.Adhesive")
		(11 "B.Adhes" user "B.Adhesive")
		(13 "F.Paste" user "Package Geometry/Pastemask Top")
		(15 "B.Paste" user "Package Geometry/Pastemask Bottom")
		(5 "F.SilkS" user "Ref Des/Silkscreen Top")
		(7 "B.SilkS" user "Ref Des/Silkscreen Bottom")
		(1 "F.Mask" user "Board Geometry/Soldermask Top")
		(3 "B.Mask" user "Board Geometry/Soldermask Bottom")
		(17 "Dwgs.User" user "User.Drawings")
		(19 "Cmts.User" user "User.Comments")
		(21 "Eco1.User" user "User.Eco1")
		(23 "Eco2.User" user "User.Eco2")
		(25 "Edge.Cuts" user "Board Geometry/Outline")
		(27 "Margin" user)
		(31 "F.CrtYd" user "Package Geometry/Place Bound Top")
		(29 "B.CrtYd" user "Package Geometry/Place Bound Bottom")
		(35 "F.Fab" user "Ref Des/Assembly Top")
		(33 "B.Fab" user "Ref Des/Assembly Bottom")
	)
	(footprint ""
		(layer "F.Cu")
		(at 452.567802 -51.019456)
		(property "Reference" "PC447"
			(at 0 0 0)
			(layer "F.SilkS")
			(hide yes)
			(effects
				(font
					(size 1.27 1.27)
				)
			)
		)
		(property "Value" ""
			(at 0 0 0)
			(layer "F.Fab")
			(effects
				(font
					(size 1.27 1.27)
				)
			)
		)
		(duplicate_pad_numbers_are_jumpers no)
		(fp_line
			(start -0.7874 -0.4064)
			(end 0.7874 -0.4064)
			(stroke
				(width 0.1524)
				(type default)
			)
			(layer "F.SilkS")
		)
		(fp_line
			(start -0.7874 0.4064)
			(end -0.7874 -0.4064)
			(stroke
				(width 0.1524)
				(type default)
			)
			(layer "F.SilkS")
		)
		(fp_line
			(start 0.7874 -0.4064)
			(end 0.7874 0.4064)
			(stroke
				(width 0.1524)
				(type default)
			)
			(layer "F.SilkS")
		)
		(fp_line
			(start 0.7874 0.4064)
			(end -0.7874 0.4064)
			(stroke
				(width 0.1524)
				(type default)
			)
			(layer "F.SilkS")
		)
		(fp_line
			(start -0.67945 -0.305054)
			(end -0.12065 -0.305054)
			(stroke
				(width 0.1)
				(type default)
			)
			(layer "F.Fab")
		)
		(fp_line
			(start -0.67945 0.3048)
			(end -0.67945 -0.305054)
			(stroke
				(width 0.1)
				(type default)
			)
			(layer "F.Fab")
		)
		(fp_line
			(start -0.12065 -0.305054)
			(end -0.12065 -0.2794)
			(stroke
				(width 0.1)
				(type default)
			)
			(layer "F.Fab")
		)
		(fp_line
			(start -0.12065 -0.2794)
			(end 0.12065 -0.2794)
			(stroke
				(width 0.1)
				(type default)
			)
			(layer "F.Fab")
		)
		(fp_line
			(start -0.12065 0.2794)
			(end -0.12065 0.3048)
			(stroke
				(width 0.1)
				(type default)
			)
			(layer "F.Fab")
		)
		(fp_line
			(start -0.12065 0.3048)
			(end -0.67945 0.3048)
			(stroke
				(width 0.1)
				(type default)
			)
			(layer "F.Fab")
		)
		(fp_line
			(start 0.120396 0.2794)
			(end -0.12065 0.2794)
			(stroke
				(width 0.1)
				(type default)
			)
			(layer "F.Fab")
		)
		(fp_line
			(start 0.120396 0.3048)
			(end 0.120396 0.2794)
			(stroke
				(width 0.1)
				(type default)
			)
			(layer "F.Fab")
		)
		(fp_line
			(start 0.12065 -0.3048)
			(end 0.67945 -0.3048)
			(stroke
				(width 0.1)
				(type default)
			)
			(layer "F.Fab")
		)
		(fp_line
			(start 0.12065 -0.2794)
			(end 0.12065 -0.3048)
			(stroke
				(width 0.1)
				(type default)
			)
			(layer "F.Fab")
		)
		(fp_line
			(start 0.67945 -0.3048)
			(end 0.67945 0.3048)
			(stroke
				(width 0.1)
				(type default)
			)
			(layer "F.Fab")
		)
		(fp_line
			(start 0.67945 0.3048)
			(end 0.120396 0.3048)
			(stroke
				(width 0.1)
				(type default)
			)
			(layer "F.Fab")
		)
		(pad "1" smd circle
			(at -0.40005 0)
			(size 0 0)
			(layers "F.Cu" "F.Mask" "F.Paste")
			(net "P12V_SSD15_SS")
		)
		(pad "2" smd circle
			(at 0.40005 0)
			(size 0 0)
			(layers "F.Cu" "F.Mask" "F.Paste")
			(net "GND")
		)
	)
	(footprint ""
		(layer "F.Cu")
		(at 454.125838 -315.944758 180)
		(property "Reference" "PC263"
			(at 0 0 180)
			(layer "F.SilkS")
			(hide yes)
			(effects
				(font
					(size 1.27 1.27)
				)
			)
		)
		(property "Value" ""
			(at 0 0 180)
			(layer "F.Fab")
			(effects
				(font
					(size 1.27 1.27)
				)
			)
		)
		(duplicate_pad_numbers_are_jumpers no)
		(fp_line
			(start 1.524 0.762)
			(end -1.524 0.762)
			(stroke
				(width 0.1524)
				(type default)
			)
			(layer "F.SilkS")
		)
		(fp_line
			(start 1.524 -0.762)
			(end 1.524 0.762)
			(stroke
				(width 0.1524)
				(type default)
			)
			(layer "F.SilkS")
		)
		(fp_line
			(start -1.524 0.762)
			(end -1.524 -0.762)
			(stroke
				(width 0.1524)
				(type default)
			)
			(layer "F.SilkS")
		)
		(fp_line
			(start -1.524 -0.762)
			(end 1.524 -0.762)
			(stroke
				(width 0.1524)
				(type default)
			)
			(layer "F.SilkS")
		)
		(fp_line
			(start 1.1049 0.724916)
			(end 1.1049 -0.724916)
			(stroke
				(width 0.1)
				(type default)
			)
			(layer "F.Fab")
		)
		(fp_line
			(start 1.1049 -0.724916)
			(end -1.1049 -0.724916)
			(stroke
				(width 0.1)
				(type default)
			)
			(layer "F.Fab")
		)
		(fp_line
			(start -1.1049 0.724916)
			(end 1.1049 0.724916)
			(stroke
				(width 0.1)
				(type default)
			)
			(layer "F.Fab")
		)
		(fp_line
			(start -1.1049 -0.724916)
			(end -1.1049 0.724916)
			(stroke
				(width 0.1)
				(type default)
			)
			(layer "F.Fab")
		)
		(pad "1" smd rect
			(at -0.889 0)
			(size 1.016 1.27)
			(layers "F.Cu" "F.Mask" "F.Paste")
			(net "SW_P12V_P1V25_PEX3_FLT")
		)
		(pad "2" smd rect
			(at 0.889 0)
			(size 1.016 1.27)
			(layers "F.Cu" "F.Mask" "F.Paste")
			(net "GND")
		)
	)
	(footprint ""
		(layer "F.Cu")
		(at 220.34373 -44.87291)
		(property "Reference" "R584"
			(at 0 0 0)
			(layer "F.SilkS")
			(hide yes)
			(effects
				(font
					(size 1.27 1.27)
				)
			)
		)
		(property "Value" ""
			(at 0 0 0)
			(layer "F.Fab")
			(effects
				(font
					(size 1.27 1.27)
				)
			)
		)
		(duplicate_pad_numbers_are_jumpers no)
		(fp_line
			(start -0.7874 -0.4064)
			(end 0.7874 -0.4064)
			(stroke
				(width 0.1524)
				(type default)
			)
			(layer "F.SilkS")
		)
		(fp_line
			(start -0.7874 0.4064)
			(end -0.7874 -0.4064)
			(stroke
				(width 0.1524)
				(type default)
			)
			(layer "F.SilkS")
		)
		(fp_line
			(start 0.7874 -0.4064)
			(end 0.7874 0.4064)
			(stroke
				(width 0.1524)
				(type default)
			)
			(layer "F.SilkS")
		)
		(fp_line
			(start 0.7874 0.4064)
			(end -0.7874 0.4064)
			(stroke
				(width 0.1524)
				(type default)
			)
			(layer "F.SilkS")
		)
		(fp_line
			(start -0.67945 -0.305054)
			(end -0.12065 -0.305054)
			(stroke
				(width 0.1)
				(type default)
			)
			(layer "F.Fab")
		)
		(fp_line
			(start -0.67945 0.3048)
			(end -0.67945 -0.305054)
			(stroke
				(width 0.1)
				(type default)
			)
			(layer "F.Fab")
		)
		(fp_line
			(start -0.12065 -0.305054)
			(end -0.12065 -0.2794)
			(stroke
				(width 0.1)
				(type default)
			)
			(layer "F.Fab")
		)
		(fp_line
			(start -0.12065 -0.2794)
			(end 0.12065 -0.2794)
			(stroke
				(width 0.1)
				(type default)
			)
			(layer "F.Fab")
		)
		(fp_line
			(start -0.12065 0.2794)
			(end -0.12065 0.3048)
			(stroke
				(width 0.1)
				(type default)
			)
			(layer "F.Fab")
		)
		(fp_line
			(start -0.12065 0.3048)
			(end -0.67945 0.3048)
			(stroke
				(width 0.1)
				(type default)
			)
			(layer "F.Fab")
		)
		(fp_line
			(start 0.120396 0.2794)
			(end -0.12065 0.2794)
			(stroke
				(width 0.1)
				(type default)
			)
			(layer "F.Fab")
		)
		(fp_line
			(start 0.120396 0.3048)
			(end 0.120396 0.2794)
			(stroke
				(width 0.1)
				(type default)
			)
			(layer "F.Fab")
		)
		(fp_line
			(start 0.12065 -0.3048)
			(end 0.67945 -0.3048)
			(stroke
				(width 0.1)
				(type default)
			)
			(layer "F.Fab")
		)
		(fp_line
			(start 0.12065 -0.2794)
			(end 0.12065 -0.3048)
			(stroke
				(width 0.1)
				(type default)
			)
			(layer "F.Fab")
		)
		(fp_line
			(start 0.67945 -0.3048)
			(end 0.67945 0.3048)
			(stroke
				(width 0.1)
				(type default)
			)
			(layer "F.Fab")
		)
		(fp_line
			(start 0.67945 0.3048)
			(end 0.120396 0.3048)
			(stroke
				(width 0.1)
				(type default)
			)
			(layer "F.Fab")
		)
		(pad "1" smd circle
			(at -0.40005 0)
			(size 0 0)
			(layers "F.Cu" "F.Mask" "F.Paste")
			(net "SSD7_ADC_A0")
		)
		(pad "2" smd circle
			(at 0.40005 0)
			(size 0 0)
			(layers "F.Cu" "F.Mask" "F.Paste")
			(net "P3V3_AUX")
		)
	)
	(footprint ""
		(layer "F.Cu")
		(at 134.513828 -350.098614 90)
		(property "Reference" "C2254"
			(at 0 0 90)
			(layer "F.SilkS")
			(hide yes)
			(effects
				(font
					(size 1.27 1.27)
				)
			)
		)
		(property "Value" ""
			(at 0 0 90)
			(layer "F.Fab")
			(effects
				(font
					(size 1.27 1.27)
				)
			)
		)
		(duplicate_pad_numbers_are_jumpers no)
		(fp_line
			(start 0.299974 -0.150114)
			(end 0.299974 0.150114)
			(stroke
				(width 0.1)
				(type default)
			)
			(layer "F.Fab")
		)
		(fp_line
			(start -0.299974 -0.150114)
			(end 0.299974 -0.150114)
			(stroke
				(width 0.1)
				(type default)
			)
			(layer "F.Fab")
		)
		(fp_line
			(start 0.299974 0.150114)
			(end -0.299974 0.150114)
			(stroke
				(width 0.1)
				(type default)
			)
			(layer "F.Fab")
		)
		(fp_line
			(start -0.299974 0.150114)
			(end -0.299974 -0.150114)
			(stroke
				(width 0.1)
				(type default)
			)
			(layer "F.Fab")
		)
		(pad "1" smd rect
			(at -0.2667 0 90)
			(size 0.3048 0.381)
			(layers "F.Cu" "F.Mask" "F.Paste")
			(net "P5E_PEX1_STN5_TX_DN<90>")
		)
		(pad "2" smd rect
			(at 0.2667 0 90)
			(size 0.3048 0.381)
			(layers "F.Cu" "F.Mask" "F.Paste")
			(net "P5E_PEX1_STN5_TX_C_DN<90>")
		)
	)
	(footprint ""
		(layer "F.Cu")
		(at 96.638618 -22.867366 90)
		(property "Reference" "C3897"
			(at 0 0 90)
			(layer "F.SilkS")
			(hide yes)
			(effects
				(font
					(size 1.27 1.27)
				)
			)
		)
		(property "Value" ""
			(at 0 0 90)
			(layer "F.Fab")
			(effects
				(font
					(size 1.27 1.27)
				)
			)
		)
		(duplicate_pad_numbers_are_jumpers no)
		(fp_line
			(start 0.7874 -0.4064)
			(end 0.7874 0.4064)
			(stroke
				(width 0.1524)
				(type default)
			)
			(layer "F.SilkS")
		)
		(fp_line
			(start -0.7874 -0.4064)
			(end 0.7874 -0.4064)
			(stroke
				(width 0.1524)
				(type default)
			)
			(layer "F.SilkS")
		)
		(fp_line
			(start 0.7874 0.4064)
			(end -0.7874 0.4064)
			(stroke
				(width 0.1524)
				(type default)
			)
			(layer "F.SilkS")
		)
		(fp_line
			(start -0.7874 0.4064)
			(end -0.7874 -0.4064)
			(stroke
				(width 0.1524)
				(type default)
			)
			(layer "F.SilkS")
		)
		(fp_line
			(start -0.12065 -0.305054)
			(end -0.12065 -0.2794)
			(stroke
				(width 0.1)
				(type default)
			)
			(layer "F.Fab")
		)
		(fp_line
			(start -0.67945 -0.305054)
			(end -0.12065 -0.305054)
			(stroke
				(width 0.1)
				(type default)
			)
			(layer "F.Fab")
		)
		(fp_line
			(start 0.67945 -0.3048)
			(end 0.67945 0.3048)
			(stroke
				(width 0.1)
				(type default)
			)
			(layer "F.Fab")
		)
		(fp_line
			(start 0.12065 -0.3048)
			(end 0.67945 -0.3048)
			(stroke
				(width 0.1)
				(type default)
			)
			(layer "F.Fab")
		)
		(fp_line
			(start 0.12065 -0.2794)
			(end 0.12065 -0.3048)
			(stroke
				(width 0.1)
				(type default)
			)
			(layer "F.Fab")
		)
		(fp_line
			(start -0.12065 -0.2794)
			(end 0.12065 -0.2794)
			(stroke
				(width 0.1)
				(type default)
			)
			(layer "F.Fab")
		)
		(fp_line
			(start 0.120396 0.2794)
			(end -0.12065 0.2794)
			(stroke
				(width 0.1)
				(type default)
			)
			(layer "F.Fab")
		)
		(fp_line
			(start -0.12065 0.2794)
			(end -0.12065 0.3048)
			(stroke
				(width 0.1)
				(type default)
			)
			(layer "F.Fab")
		)
		(fp_line
			(start 0.67945 0.3048)
			(end 0.120396 0.3048)
			(stroke
				(width 0.1)
				(type default)
			)
			(layer "F.Fab")
		)
		(fp_line
			(start 0.120396 0.3048)
			(end 0.120396 0.2794)
			(stroke
				(width 0.1)
				(type default)
			)
			(layer "F.Fab")
		)
		(fp_line
			(start -0.12065 0.3048)
			(end -0.67945 0.3048)
			(stroke
				(width 0.1)
				(type default)
			)
			(layer "F.Fab")
		)
		(fp_line
			(start -0.67945 0.3048)
			(end -0.67945 -0.305054)
			(stroke
				(width 0.1)
				(type default)
			)
			(layer "F.Fab")
		)
		(pad "1" smd circle
			(at -0.40005 0 90)
			(size 0 0)
			(layers "F.Cu" "F.Mask" "F.Paste")
			(net "P12V_SSD3")
		)
		(pad "2" smd circle
			(at 0.40005 0 90)
			(size 0 0)
			(layers "F.Cu" "F.Mask" "F.Paste")
			(net "GND")
		)
	)
	(footprint ""
		(layer "F.Cu")
		(at 98.048318 -393.1158 180)
		(property "Reference" "R5457"
			(at 0 0 180)
			(layer "F.SilkS")
			(hide yes)
			(effects
				(font
					(size 1.27 1.27)
				)
			)
		)
		(property "Value" ""
			(at 0 0 180)
			(layer "F.Fab")
			(effects
				(font
					(size 1.27 1.27)
				)
			)
		)
		(duplicate_pad_numbers_are_jumpers no)
		(fp_line
			(start 0.7874 0.4064)
			(end -0.7874 0.4064)
			(stroke
				(width 0.1524)
				(type default)
			)
			(layer "F.SilkS")
		)
		(fp_line
			(start 0.7874 -0.4064)
			(end 0.7874 0.4064)
			(stroke
				(width 0.1524)
				(type default)
			)
			(layer "F.SilkS")
		)
		(fp_line
			(start -0.7874 0.4064)
			(end -0.7874 -0.4064)
			(stroke
				(width 0.1524)
				(type default)
			)
			(layer "F.SilkS")
		)
		(fp_line
			(start -0.7874 -0.4064)
			(end 0.7874 -0.4064)
			(stroke
				(width 0.1524)
				(type default)
			)
			(layer "F.SilkS")
		)
		(fp_line
			(start 0.67945 0.3048)
			(end 0.120396 0.3048)
			(stroke
				(width 0.1)
				(type default)
			)
			(layer "F.Fab")
		)
		(fp_line
			(start 0.67945 -0.3048)
			(end 0.67945 0.3048)
			(stroke
				(width 0.1)
				(type default)
			)
			(layer "F.Fab")
		)
		(fp_line
			(start 0.12065 -0.2794)
			(end 0.12065 -0.3048)
			(stroke
				(width 0.1)
				(type default)
			)
			(layer "F.Fab")
		)
		(fp_line
			(start 0.12065 -0.3048)
			(end 0.67945 -0.3048)
			(stroke
				(width 0.1)
				(type default)
			)
			(layer "F.Fab")
		)
		(fp_line
			(start 0.120396 0.3048)
			(end 0.120396 0.2794)
			(stroke
				(width 0.1)
				(type default)
			)
			(layer "F.Fab")
		)
		(fp_line
			(start 0.120396 0.2794)
			(end -0.12065 0.2794)
			(stroke
				(width 0.1)
				(type default)
			)
			(layer "F.Fab")
		)
		(fp_line
			(start -0.12065 0.3048)
			(end -0.67945 0.3048)
			(stroke
				(width 0.1)
				(type default)
			)
			(layer "F.Fab")
		)
		(fp_line
			(start -0.12065 0.2794)
			(end -0.12065 0.3048)
			(stroke
				(width 0.1)
				(type default)
			)
			(layer "F.Fab")
		)
		(fp_line
			(start -0.12065 -0.2794)
			(end 0.12065 -0.2794)
			(stroke
				(width 0.1)
				(type default)
			)
			(layer "F.Fab")
		)
		(fp_line
			(start -0.12065 -0.305054)
			(end -0.12065 -0.2794)
			(stroke
				(width 0.1)
				(type default)
			)
			(layer "F.Fab")
		)
		(fp_line
			(start -0.67945 0.3048)
			(end -0.67945 -0.305054)
			(stroke
				(width 0.1)
				(type default)
			)
			(layer "F.Fab")
		)
		(fp_line
			(start -0.67945 -0.305054)
			(end -0.12065 -0.305054)
			(stroke
				(width 0.1)
				(type default)
			)
			(layer "F.Fab")
		)
		(pad "1" smd circle
			(at -0.40005 0 180)
			(size 0 0)
			(layers "F.Cu" "F.Mask" "F.Paste")
			(net "BIC_USB_HUB_PGANG")
		)
		(pad "2" smd circle
			(at 0.40005 0 180)
			(size 0 0)
			(layers "F.Cu" "F.Mask" "F.Paste")
			(net "GND")
		)
	)
	(footprint ""
		(layer "F.Cu")
		(at 428.319438 -119.584724 180)
		(property "Reference" "C664"
			(at 0 0 180)
			(layer "F.SilkS")
			(hide yes)
			(effects
				(font
					(size 1.27 1.27)
				)
			)
		)
		(property "Value" ""
			(at 0 0 180)
			(layer "F.Fab")
			(effects
				(font
					(size 1.27 1.27)
				)
			)
		)
		(duplicate_pad_numbers_are_jumpers no)
		(fp_line
			(start 0.299974 0.150114)
			(end -0.299974 0.150114)
			(stroke
				(width 0.1)
				(type default)
			)
			(layer "F.Fab")
		)
		(fp_line
			(start 0.299974 -0.150114)
			(end 0.299974 0.150114)
			(stroke
				(width 0.1)
				(type default)
			)
			(layer "F.Fab")
		)
		(fp_line
			(start -0.299974 0.150114)
			(end -0.299974 -0.150114)
			(stroke
				(width 0.1)
				(type default)
			)
			(layer "F.Fab")
		)
		(fp_line
			(start -0.299974 -0.150114)
			(end 0.299974 -0.150114)
			(stroke
				(width 0.1)
				(type default)
			)
			(layer "F.Fab")
		)
		(pad "1" smd rect
			(at -0.2667 0 180)
			(size 0.3048 0.381)
			(layers "F.Cu" "F.Mask" "F.Paste")
			(net "P5E_PEX3_STN0_TX_DP<0>")
		)
		(pad "2" smd rect
			(at 0.2667 0 180)
			(size 0.3048 0.381)
			(layers "F.Cu" "F.Mask" "F.Paste")
			(net "P5E_PEX3_STN0_TX_C_DP<0>")
		)
	)
	(footprint ""
		(layer "F.Cu")
		(at 160.026604 -25.432004 -90)
		(property "Reference" "C970"
			(at 0 0 270)
			(layer "F.SilkS")
			(hide yes)
			(effects
				(font
					(size 1.27 1.27)
				)
			)
		)
		(property "Value" ""
			(at 0 0 270)
			(layer "F.Fab")
			(effects
				(font
					(size 1.27 1.27)
				)
			)
		)
		(duplicate_pad_numbers_are_jumpers no)
		(fp_line
			(start -0.7874 0.4064)
			(end -0.7874 -0.4064)
			(stroke
				(width 0.1524)
				(type default)
			)
			(layer "F.SilkS")
		)
		(fp_line
			(start 0.7874 0.4064)
			(end -0.7874 0.4064)
			(stroke
				(width 0.1524)
				(type default)
			)
			(layer "F.SilkS")
		)
		(fp_line
			(start -0.7874 -0.4064)
			(end 0.7874 -0.4064)
			(stroke
				(width 0.1524)
				(type default)
			)
			(layer "F.SilkS")
		)
		(fp_line
			(start 0.7874 -0.4064)
			(end 0.7874 0.4064)
			(stroke
				(width 0.1524)
				(type default)
			)
			(layer "F.SilkS")
		)
		(fp_line
			(start -0.67945 0.3048)
			(end -0.67945 -0.305054)
			(stroke
				(width 0.1)
				(type default)
			)
			(layer "F.Fab")
		)
		(fp_line
			(start -0.12065 0.3048)
			(end -0.67945 0.3048)
			(stroke
				(width 0.1)
				(type default)
			)
			(layer "F.Fab")
		)
		(fp_line
			(start 0.120396 0.3048)
			(end 0.120396 0.2794)
			(stroke
				(width 0.1)
				(type default)
			)
			(layer "F.Fab")
		)
		(fp_line
			(start 0.67945 0.3048)
			(end 0.120396 0.3048)
			(stroke
				(width 0.1)
				(type default)
			)
			(layer "F.Fab")
		)
		(fp_line
			(start -0.12065 0.2794)
			(end -0.12065 0.3048)
			(stroke
				(width 0.1)
				(type default)
			)
			(layer "F.Fab")
		)
		(fp_line
			(start 0.120396 0.2794)
			(end -0.12065 0.2794)
			(stroke
				(width 0.1)
				(type default)
			)
			(layer "F.Fab")
		)
		(fp_line
			(start -0.12065 -0.2794)
			(end 0.12065 -0.2794)
			(stroke
				(width 0.1)
				(type default)
			)
			(layer "F.Fab")
		)
		(fp_line
			(start 0.12065 -0.2794)
			(end 0.12065 -0.3048)
			(stroke
				(width 0.1)
				(type default)
			)
			(layer "F.Fab")
		)
		(fp_line
			(start 0.12065 -0.3048)
			(end 0.67945 -0.3048)
			(stroke
				(width 0.1)
				(type default)
			)
			(layer "F.Fab")
		)
		(fp_line
			(start 0.67945 -0.3048)
			(end 0.67945 0.3048)
			(stroke
				(width 0.1)
				(type default)
			)
			(layer "F.Fab")
		)
		(fp_line
			(start -0.67945 -0.305054)
			(end -0.12065 -0.305054)
			(stroke
				(width 0.1)
				(type default)
			)
			(layer "F.Fab")
		)
		(fp_line
			(start -0.12065 -0.305054)
			(end -0.12065 -0.2794)
			(stroke
				(width 0.1)
				(type default)
			)
			(layer "F.Fab")
		)
		(pad "1" smd circle
			(at -0.40005 0 270)
			(size 0 0)
			(layers "F.Cu" "F.Mask" "F.Paste")
			(net "GND")
		)
		(pad "2" smd circle
			(at 0.40005 0 270)
			(size 0 0)
			(layers "F.Cu" "F.Mask" "F.Paste")
			(net "P3V3_SSD5")
		)
	)
)
